# T6G (Grand Teton) — schematic netlist excerpt (pin names and nets, part order shuffled) for the footprints in the layout excerpt that follows; sources: Cadence DE-HDL packaged netlist, KiCad conversion of 04192023_DAF0TMB3IC0_F0TG_MB_C_brd_V02_OCP.brd

PR6007  Q_RES  20K 1% CHIP  pkg 0402LF  page 269 : A = P1V8_AUX_FB ; B = P1V8_AUX
C667  Q_CAP  22UF 4V 20% X6S  pkg C0402  page 301 : A = P1V8_CPU0_RT_1D ; B = GND

(kicad_pcb
	(version 20260206)
	(generator "pcbnew")
	(generator_version "10.0")
	(general
		(thickness 1.6)
		(legacy_teardrops no)
	)
	(paper "A4")
	(title_block
		(title "04192023_DAF0TMB3IC0_F0TG_MB_C_brd_V02_OCP.brd")
		(comment 1 "Grand Teton / footprints 2433-2434 of 8354")
	)
	(layers
		(0 "F.Cu" signal "TOP")
		(4 "In1.Cu" signal "GND")
		(6 "In2.Cu" signal "IN1")
		(8 "In3.Cu" signal "GND1")
		(10 "In4.Cu" signal "IN2")
		(12 "In5.Cu" signal "GND2")
		(14 "In6.Cu" signal "IN3")
		(16 "In7.Cu" signal "GND3")
		(18 "In8.Cu" signal "VCC")
		(20 "In9.Cu" signal "VCC1")
		(22 "In10.Cu" signal "GND4")
		(24 "In11.Cu" signal "IN4")
		(26 "In12.Cu" signal "GND5")
		(28 "In13.Cu" signal "IN5")
		(30 "In14.Cu" signal "GND6")
		(32 "In15.Cu" signal "IN6")
		(34 "In16.Cu" signal "GND7")
		(2 "B.Cu" signal "BOTTOM")
		(9 "F.Adhes" user "F.Adhesive")
		(11 "B.Adhes" user "B.Adhesive")
		(13 "F.Paste" user "Package Geometry/Pastemask Top")
		(15 "B.Paste" user "Package Geometry/Pastemask Bottom")
		(5 "F.SilkS" user "Ref Des/Silkscreen Top")
		(7 "B.SilkS" user "Ref Des/Silkscreen Bottom")
		(1 "F.Mask" user "Board Geometry/Soldermask Top")
		(3 "B.Mask" user "Board Geometry/Soldermask Bottom")
		(17 "Dwgs.User" user "User.Drawings")
		(19 "Cmts.User" user "User.Comments")
		(21 "Eco1.User" user "User.Eco1")
		(23 "Eco2.User" user "User.Eco2")
		(25 "Edge.Cuts" user "Board Geometry/Outline")
		(27 "Margin" user)
		(31 "F.CrtYd" user "Package Geometry/Place Bound Top")
		(29 "B.CrtYd" user "Package Geometry/Place Bound Bottom")
		(35 "F.Fab" user "Ref Des/Assembly Top")
		(33 "B.Fab" user "Ref Des/Assembly Bottom")
	)
	(footprint ""
		(layer "F.Cu")
		(at 142.729712 -73.623932)
		(property "Reference" "PR6007"
			(at 0 0 0)
			(layer "F.SilkS")
			(hide yes)
			(effects
				(font
					(size 1.27 1.27)
				)
			)
		)
		(property "Value" ""
			(at 0 0 0)
			(layer "F.Fab")
			(effects
				(font
					(size 1.27 1.27)
				)
			)
		)
		(duplicate_pad_numbers_are_jumpers no)
		(fp_line
			(start -0.7874 -0.4064)
			(end 0.7874 -0.4064)
			(stroke
				(width 0.1524)
				(type default)
			)
			(layer "F.SilkS")
		)
		(fp_line
			(start -0.7874 0.4064)
			(end -0.7874 -0.4064)
			(stroke
				(width 0.1524)
				(type default)
			)
			(layer "F.SilkS")
		)
		(fp_line
			(start 0.7874 -0.4064)
			(end 0.7874 0.4064)
			(stroke
				(width 0.1524)
				(type default)
			)
			(layer "F.SilkS")
		)
		(fp_line
			(start 0.7874 0.4064)
			(end -0.7874 0.4064)
			(stroke
				(width 0.1524)
				(type default)
			)
			(layer "F.SilkS")
		)
		(fp_line
			(start -0.67945 -0.305054)
			(end -0.12065 -0.305054)
			(stroke
				(width 0.1)
				(type default)
			)
			(layer "F.Fab")
		)
		(fp_line
			(start -0.67945 0.3048)
			(end -0.67945 -0.305054)
			(stroke
				(width 0.1)
				(type default)
			)
			(layer "F.Fab")
		)
		(fp_line
			(start -0.12065 -0.305054)
			(end -0.12065 -0.2794)
			(stroke
				(width 0.1)
				(type default)
			)
			(layer "F.Fab")
		)
		(fp_line
			(start -0.12065 -0.2794)
			(end 0.12065 -0.2794)
			(stroke
				(width 0.1)
				(type default)
			)
			(layer "F.Fab")
		)
		(fp_line
			(start -0.12065 0.2794)
			(end -0.12065 0.3048)
			(stroke
				(width 0.1)
				(type default)
			)
			(layer "F.Fab")
		)
		(fp_line
			(start -0.12065 0.3048)
			(end -0.67945 0.3048)
			(stroke
				(width 0.1)
				(type default)
			)
			(layer "F.Fab")
		)
		(fp_line
			(start 0.120396 0.2794)
			(end -0.12065 0.2794)
			(stroke
				(width 0.1)
				(type default)
			)
			(layer "F.Fab")
		)
		(fp_line
			(start 0.120396 0.3048)
			(end 0.120396 0.2794)
			(stroke
				(width 0.1)
				(type default)
			)
			(layer "F.Fab")
		)
		(fp_line
			(start 0.12065 -0.3048)
			(end 0.67945 -0.3048)
			(stroke
				(width 0.1)
				(type default)
			)
			(layer "F.Fab")
		)
		(fp_line
			(start 0.12065 -0.2794)
			(end 0.12065 -0.3048)
			(stroke
				(width 0.1)
				(type default)
			)
			(layer "F.Fab")
		)
		(fp_line
			(start 0.67945 -0.3048)
			(end 0.67945 0.3048)
			(stroke
				(width 0.1)
				(type default)
			)
			(layer "F.Fab")
		)
		(fp_line
			(start 0.67945 0.3048)
			(end 0.120396 0.3048)
			(stroke
				(width 0.1)
				(type default)
			)
			(layer "F.Fab")
		)
		(pad "1" smd circle
			(at -0.40005 0)
			(size 0 0)
			(layers "F.Cu" "F.Mask" "F.Paste")
			(net "P1V8_AUX_FB")
		)
		(pad "2" smd circle
			(at 0.40005 0)
			(size 0 0)
			(layers "F.Cu" "F.Mask" "F.Paste")
			(net "P1V8_AUX")
		)
	)
	(footprint ""
		(layer "F.Cu")
		(at 430.664366 -392.879072 -90)
		(property "Reference" "C667"
			(at 0 0 270)
			(layer "F.SilkS")
			(hide yes)
			(effects
				(font
					(size 1.27 1.27)
				)
			)
		)
		(property "Value" ""
			(at 0 0 270)
			(layer "F.Fab")
			(effects
				(font
					(size 1.27 1.27)
				)
			)
		)
		(duplicate_pad_numbers_are_jumpers no)
		(fp_line
			(start -0.7874 0.4064)
			(end -0.7874 -0.4064)
			(stroke
				(width 0.1524)
				(type default)
			)
			(layer "F.SilkS")
		)
		(fp_line
			(start 0.7874 0.4064)
			(end -0.7874 0.4064)
			(stroke
				(width 0.1524)
				(type default)
			)
			(layer "F.SilkS")
		)
		(fp_line
			(start -0.7874 -0.4064)
			(end 0.7874 -0.4064)
			(stroke
				(width 0.1524)
				(type default)
			)
			(layer "F.SilkS")
		)
		(fp_line
			(start 0.7874 -0.4064)
			(end 0.7874 0.4064)
			(stroke
				(width 0.1524)
				(type default)
			)
			(layer "F.SilkS")
		)
		(fp_line
			(start -0.67945 0.3048)
			(end -0.67945 -0.305054)
			(stroke
				(width 0.1)
				(type default)
			)
			(layer "F.Fab")
		)
		(fp_line
			(start -0.12065 0.3048)
			(end -0.67945 0.3048)
			(stroke
				(width 0.1)
				(type default)
			)
			(layer "F.Fab")
		)
		(fp_line
			(start 0.120396 0.3048)
			(end 0.120396 0.2794)
			(stroke
				(width 0.1)
				(type default)
			)
			(layer "F.Fab")
		)
		(fp_line
			(start 0.67945 0.3048)
			(end 0.120396 0.3048)
			(stroke
				(width 0.1)
				(type default)
			)
			(layer "F.Fab")
		)
		(fp_line
			(start -0.12065 0.2794)
			(end -0.12065 0.3048)
			(stroke
				(width 0.1)
				(type default)
			)
			(layer "F.Fab")
		)
		(fp_line
			(start 0.120396 0.2794)
			(end -0.12065 0.2794)
			(stroke
				(width 0.1)
				(type default)
			)
			(layer "F.Fab")
		)
		(fp_line
			(start -0.12065 -0.2794)
			(end 0.12065 -0.2794)
			(stroke
				(width 0.1)
				(type default)
			)
			(layer "F.Fab")
		)
		(fp_line
			(start 0.12065 -0.2794)
			(end 0.12065 -0.3048)
			(stroke
				(width 0.1)
				(type default)
			)
			(layer "F.Fab")
		)
		(fp_line
			(start 0.12065 -0.3048)
			(end 0.67945 -0.3048)
			(stroke
				(width 0.1)
				(type default)
			)
			(layer "F.Fab")
		)
		(fp_line
			(start 0.67945 -0.3048)
			(end 0.67945 0.3048)
			(stroke
				(width 0.1)
				(type default)
			)
			(layer "F.Fab")
		)
		(fp_line
			(start -0.67945 -0.305054)
			(end -0.12065 -0.305054)
			(stroke
				(width 0.1)
				(type default)
			)
			(layer "F.Fab")
		)
		(fp_line
			(start -0.12065 -0.305054)
			(end -0.12065 -0.2794)
			(stroke
				(width 0.1)
				(type default)
			)
			(layer "F.Fab")
		)
		(pad "1" smd circle
			(at -0.40005 0 270)
			(size 0 0)
			(layers "F.Cu" "F.Mask" "F.Paste")
			(net "P1V8_CPU0_RT_1D")
		)
		(pad "2" smd circle
			(at 0.40005 0 270)
			(size 0 0)
			(layers "F.Cu" "F.Mask" "F.Paste")
			(net "GND")
		)
	)
)
